(kicad_pcb
	(version 20260206)
	(generator "pcbnew")
	(generator_version "10.0")
	(general
		(thickness 1.6)
		(legacy_teardrops no)
	)
	(paper "A4")
	(title_block
		(title "03242023_DA0F0TMBIJ0_F0T_Motherboard_J_brd_V01_OCP.brd")
		(comment 1 "Grand Teton / footprints 2353-2358 of 6105")
	)
	(layers
		(0 "F.Cu" signal "TOP")
		(4 "In1.Cu" signal "GND")
		(6 "In2.Cu" signal "IN1")
		(8 "In3.Cu" signal "GND1")
		(10 "In4.Cu" signal "IN2")
		(12 "In5.Cu" signal "GND2")
		(14 "In6.Cu" signal "IN3")
		(16 "In7.Cu" signal "GND3")
		(18 "In8.Cu" signal "VCC")
		(20 "In9.Cu" signal "VCC1")
		(22 "In10.Cu" signal "GND4")
		(24 "In11.Cu" signal "IN4")
		(26 "In12.Cu" signal "GND5")
		(28 "In13.Cu" signal "IN5")
		(30 "In14.Cu" signal "GND6")
		(32 "In15.Cu" signal "IN6")
		(34 "In16.Cu" signal "GND7")
		(2 "B.Cu" signal "BOTTOM")
		(9 "F.Adhes" user "F.Adhesive")
		(11 "B.Adhes" user "B.Adhesive")
		(13 "F.Paste" user "Package Geometry/Pastemask Top")
		(15 "B.Paste" user "Package Geometry/Pastemask Bottom")
		(5 "F.SilkS" user "Ref Des/Silkscreen Top")
		(7 "B.SilkS" user "Ref Des/Silkscreen Bottom")
		(1 "F.Mask" user "Board Geometry/Soldermask Top")
		(3 "B.Mask" user "Board Geometry/Soldermask Bottom")
		(17 "Dwgs.User" user "User.Drawings")
		(19 "Cmts.User" user "User.Comments")
		(21 "Eco1.User" user "User.Eco1")
		(23 "Eco2.User" user "User.Eco2")
		(25 "Edge.Cuts" user "Board Geometry/Outline")
		(27 "Margin" user)
		(31 "F.CrtYd" user "Package Geometry/Place Bound Top")
		(29 "B.CrtYd" user "Package Geometry/Place Bound Bottom")
		(35 "F.Fab" user "Ref Des/Assembly Top")
		(33 "B.Fab" user "Ref Des/Assembly Bottom")
	)
	(footprint ""
		(layer "F.Cu")
		(at 371.602 -39.969948 90)
		(property "Reference" "R750"
			(at 0 0 90)
			(layer "F.SilkS")
			(hide yes)
			(effects
				(font
					(size 1.27 1.27)
				)
			)
		)
		(property "Value" ""
			(at 0 0 90)
			(layer "F.Fab")
			(effects
				(font
					(size 1.27 1.27)
				)
			)
		)
		(duplicate_pad_numbers_are_jumpers no)
		(fp_line
			(start 0.7874 -0.4064)
			(end 0.7874 0.4064)
			(stroke
				(width 0.1524)
				(type default)
			)
			(layer "F.SilkS")
		)
		(fp_line
			(start -0.7874 -0.4064)
			(end 0.7874 -0.4064)
			(stroke
				(width 0.1524)
				(type default)
			)
			(layer "F.SilkS")
		)
		(fp_line
			(start 0.7874 0.4064)
			(end -0.7874 0.4064)
			(stroke
				(width 0.1524)
				(type default)
			)
			(layer "F.SilkS")
		)
		(fp_line
			(start -0.7874 0.4064)
			(end -0.7874 -0.4064)
			(stroke
				(width 0.1524)
				(type default)
			)
			(layer "F.SilkS")
		)
		(fp_line
			(start -0.12065 -0.305054)
			(end -0.12065 -0.2794)
			(stroke
				(width 0.1)
				(type default)
			)
			(layer "F.Fab")
		)
		(fp_line
			(start -0.67945 -0.305054)
			(end -0.12065 -0.305054)
			(stroke
				(width 0.1)
				(type default)
			)
			(layer "F.Fab")
		)
		(fp_line
			(start 0.67945 -0.3048)
			(end 0.67945 0.3048)
			(stroke
				(width 0.1)
				(type default)
			)
			(layer "F.Fab")
		)
		(fp_line
			(start 0.12065 -0.3048)
			(end 0.67945 -0.3048)
			(stroke
				(width 0.1)
				(type default)
			)
			(layer "F.Fab")
		)
		(fp_line
			(start 0.12065 -0.2794)
			(end 0.12065 -0.3048)
			(stroke
				(width 0.1)
				(type default)
			)
			(layer "F.Fab")
		)
		(fp_line
			(start -0.12065 -0.2794)
			(end 0.12065 -0.2794)
			(stroke
				(width 0.1)
				(type default)
			)
			(layer "F.Fab")
		)
		(fp_line
			(start 0.120396 0.2794)
			(end -0.12065 0.2794)
			(stroke
				(width 0.1)
				(type default)
			)
			(layer "F.Fab")
		)
		(fp_line
			(start -0.12065 0.2794)
			(end -0.12065 0.3048)
			(stroke
				(width 0.1)
				(type default)
			)
			(layer "F.Fab")
		)
		(fp_line
			(start 0.67945 0.3048)
			(end 0.120396 0.3048)
			(stroke
				(width 0.1)
				(type default)
			)
			(layer "F.Fab")
		)
		(fp_line
			(start 0.120396 0.3048)
			(end 0.120396 0.2794)
			(stroke
				(width 0.1)
				(type default)
			)
			(layer "F.Fab")
		)
		(fp_line
			(start -0.12065 0.3048)
			(end -0.67945 0.3048)
			(stroke
				(width 0.1)
				(type default)
			)
			(layer "F.Fab")
		)
		(fp_line
			(start -0.67945 0.3048)
			(end -0.67945 -0.305054)
			(stroke
				(width 0.1)
				(type default)
			)
			(layer "F.Fab")
		)
		(pad "1" smd circle
			(at -0.40005 0 90)
			(size 0 0)
			(layers "F.Cu" "F.Mask" "F.Paste")
			(net "P1V05_PCH_AUX")
		)
		(pad "2" smd circle
			(at 0.40005 0 90)
			(size 0 0)
			(layers "F.Cu" "F.Mask" "F.Paste")
			(net "H_DBP_PREQ_N_PCH")
		)
	)
	(footprint ""
		(layer "F.Cu")
		(at 361.412282 -57.898792 180)
		(property "Reference" "R753"
			(at 0 0 180)
			(layer "F.SilkS")
			(hide yes)
			(effects
				(font
					(size 1.27 1.27)
				)
			)
		)
		(property "Value" ""
			(at 0 0 180)
			(layer "F.Fab")
			(effects
				(font
					(size 1.27 1.27)
				)
			)
		)
		(duplicate_pad_numbers_are_jumpers no)
		(fp_line
			(start 0.7874 0.4064)
			(end -0.7874 0.4064)
			(stroke
				(width 0.1524)
				(type default)
			)
			(layer "F.SilkS")
		)
		(fp_line
			(start 0.7874 -0.4064)
			(end 0.7874 0.4064)
			(stroke
				(width 0.1524)
				(type default)
			)
			(layer "F.SilkS")
		)
		(fp_line
			(start -0.7874 0.4064)
			(end -0.7874 -0.4064)
			(stroke
				(width 0.1524)
				(type default)
			)
			(layer "F.SilkS")
		)
		(fp_line
			(start -0.7874 -0.4064)
			(end 0.7874 -0.4064)
			(stroke
				(width 0.1524)
				(type default)
			)
			(layer "F.SilkS")
		)
		(fp_line
			(start 0.67945 0.3048)
			(end 0.120396 0.3048)
			(stroke
				(width 0.1)
				(type default)
			)
			(layer "F.Fab")
		)
		(fp_line
			(start 0.67945 -0.3048)
			(end 0.67945 0.3048)
			(stroke
				(width 0.1)
				(type default)
			)
			(layer "F.Fab")
		)
		(fp_line
			(start 0.12065 -0.2794)
			(end 0.12065 -0.3048)
			(stroke
				(width 0.1)
				(type default)
			)
			(layer "F.Fab")
		)
		(fp_line
			(start 0.12065 -0.3048)
			(end 0.67945 -0.3048)
			(stroke
				(width 0.1)
				(type default)
			)
			(layer "F.Fab")
		)
		(fp_line
			(start 0.120396 0.3048)
			(end 0.120396 0.2794)
			(stroke
				(width 0.1)
				(type default)
			)
			(layer "F.Fab")
		)
		(fp_line
			(start 0.120396 0.2794)
			(end -0.12065 0.2794)
			(stroke
				(width 0.1)
				(type default)
			)
			(layer "F.Fab")
		)
		(fp_line
			(start -0.12065 0.3048)
			(end -0.67945 0.3048)
			(stroke
				(width 0.1)
				(type default)
			)
			(layer "F.Fab")
		)
		(fp_line
			(start -0.12065 0.2794)
			(end -0.12065 0.3048)
			(stroke
				(width 0.1)
				(type default)
			)
			(layer "F.Fab")
		)
		(fp_line
			(start -0.12065 -0.2794)
			(end 0.12065 -0.2794)
			(stroke
				(width 0.1)
				(type default)
			)
			(layer "F.Fab")
		)
		(fp_line
			(start -0.12065 -0.305054)
			(end -0.12065 -0.2794)
			(stroke
				(width 0.1)
				(type default)
			)
			(layer "F.Fab")
		)
		(fp_line
			(start -0.67945 0.3048)
			(end -0.67945 -0.305054)
			(stroke
				(width 0.1)
				(type default)
			)
			(layer "F.Fab")
		)
		(fp_line
			(start -0.67945 -0.305054)
			(end -0.12065 -0.305054)
			(stroke
				(width 0.1)
				(type default)
			)
			(layer "F.Fab")
		)
		(pad "1" smd circle
			(at -0.40005 0 180)
			(size 0 0)
			(layers "F.Cu" "F.Mask" "F.Paste")
			(net "JTAG_DBP_TDI")
		)
		(pad "2" smd circle
			(at 0.40005 0 180)
			(size 0 0)
			(layers "F.Cu" "F.Mask" "F.Paste")
			(net "JTAG_DBP_TDI_PCH")
		)
	)
	(footprint ""
		(layer "F.Cu")
		(at 461.593946 -108.694728)
		(property "Reference" "R1148"
			(at 0 0 0)
			(layer "F.SilkS")
			(hide yes)
			(effects
				(font
					(size 1.27 1.27)
				)
			)
		)
		(property "Value" ""
			(at 0 0 0)
			(layer "F.Fab")
			(effects
				(font
					(size 1.27 1.27)
				)
			)
		)
		(duplicate_pad_numbers_are_jumpers no)
		(fp_line
			(start -0.7874 -0.4064)
			(end 0.7874 -0.4064)
			(stroke
				(width 0.1524)
				(type default)
			)
			(layer "F.SilkS")
		)
		(fp_line
			(start -0.7874 0.4064)
			(end -0.7874 -0.4064)
			(stroke
				(width 0.1524)
				(type default)
			)
			(layer "F.SilkS")
		)
		(fp_line
			(start 0.7874 -0.4064)
			(end 0.7874 0.4064)
			(stroke
				(width 0.1524)
				(type default)
			)
			(layer "F.SilkS")
		)
		(fp_line
			(start 0.7874 0.4064)
			(end -0.7874 0.4064)
			(stroke
				(width 0.1524)
				(type default)
			)
			(layer "F.SilkS")
		)
		(fp_line
			(start -0.67945 -0.305054)
			(end -0.12065 -0.305054)
			(stroke
				(width 0.1)
				(type default)
			)
			(layer "F.Fab")
		)
		(fp_line
			(start -0.67945 0.3048)
			(end -0.67945 -0.305054)
			(stroke
				(width 0.1)
				(type default)
			)
			(layer "F.Fab")
		)
		(fp_line
			(start -0.12065 -0.305054)
			(end -0.12065 -0.2794)
			(stroke
				(width 0.1)
				(type default)
			)
			(layer "F.Fab")
		)
		(fp_line
			(start -0.12065 -0.2794)
			(end 0.12065 -0.2794)
			(stroke
				(width 0.1)
				(type default)
			)
			(layer "F.Fab")
		)
		(fp_line
			(start -0.12065 0.2794)
			(end -0.12065 0.3048)
			(stroke
				(width 0.1)
				(type default)
			)
			(layer "F.Fab")
		)
		(fp_line
			(start -0.12065 0.3048)
			(end -0.67945 0.3048)
			(stroke
				(width 0.1)
				(type default)
			)
			(layer "F.Fab")
		)
		(fp_line
			(start 0.120396 0.2794)
			(end -0.12065 0.2794)
			(stroke
				(width 0.1)
				(type default)
			)
			(layer "F.Fab")
		)
		(fp_line
			(start 0.120396 0.3048)
			(end 0.120396 0.2794)
			(stroke
				(width 0.1)
				(type default)
			)
			(layer "F.Fab")
		)
		(fp_line
			(start 0.12065 -0.3048)
			(end 0.67945 -0.3048)
			(stroke
				(width 0.1)
				(type default)
			)
			(layer "F.Fab")
		)
		(fp_line
			(start 0.12065 -0.2794)
			(end 0.12065 -0.3048)
			(stroke
				(width 0.1)
				(type default)
			)
			(layer "F.Fab")
		)
		(fp_line
			(start 0.67945 -0.3048)
			(end 0.67945 0.3048)
			(stroke
				(width 0.1)
				(type default)
			)
			(layer "F.Fab")
		)
		(fp_line
			(start 0.67945 0.3048)
			(end 0.120396 0.3048)
			(stroke
				(width 0.1)
				(type default)
			)
			(layer "F.Fab")
		)
		(pad "1" smd circle
			(at -0.40005 0)
			(size 0 0)
			(layers "F.Cu" "F.Mask" "F.Paste")
			(net "HP_LVC3_OCP_V3_1_PRSNT2_N_R")
		)
		(pad "2" smd circle
			(at 0.40005 0)
			(size 0 0)
			(layers "F.Cu" "F.Mask" "F.Paste")
			(net "HP_LVC3_OCP_V3_1_PRSNT2_N")
		)
	)
	(footprint ""
		(layer "F.Cu")
		(at 299.02023 -51.352196)
		(property "Reference" "R2232"
			(at 0 0 0)
			(layer "F.SilkS")
			(hide yes)
			(effects
				(font
					(size 1.27 1.27)
				)
			)
		)
		(property "Value" ""
			(at 0 0 0)
			(layer "F.Fab")
			(effects
				(font
					(size 1.27 1.27)
				)
			)
		)
		(duplicate_pad_numbers_are_jumpers no)
		(fp_line
			(start -0.7874 -0.4064)
			(end 0.7874 -0.4064)
			(stroke
				(width 0.1524)
				(type default)
			)
			(layer "F.SilkS")
		)
		(fp_line
			(start -0.7874 0.4064)
			(end -0.7874 -0.4064)
			(stroke
				(width 0.1524)
				(type default)
			)
			(layer "F.SilkS")
		)
		(fp_line
			(start 0.7874 -0.4064)
			(end 0.7874 0.4064)
			(stroke
				(width 0.1524)
				(type default)
			)
			(layer "F.SilkS")
		)
		(fp_line
			(start 0.7874 0.4064)
			(end -0.7874 0.4064)
			(stroke
				(width 0.1524)
				(type default)
			)
			(layer "F.SilkS")
		)
		(fp_line
			(start -0.67945 -0.305054)
			(end -0.12065 -0.305054)
			(stroke
				(width 0.1)
				(type default)
			)
			(layer "F.Fab")
		)
		(fp_line
			(start -0.67945 0.3048)
			(end -0.67945 -0.305054)
			(stroke
				(width 0.1)
				(type default)
			)
			(layer "F.Fab")
		)
		(fp_line
			(start -0.12065 -0.305054)
			(end -0.12065 -0.2794)
			(stroke
				(width 0.1)
				(type default)
			)
			(layer "F.Fab")
		)
		(fp_line
			(start -0.12065 -0.2794)
			(end 0.12065 -0.2794)
			(stroke
				(width 0.1)
				(type default)
			)
			(layer "F.Fab")
		)
		(fp_line
			(start -0.12065 0.2794)
			(end -0.12065 0.3048)
			(stroke
				(width 0.1)
				(type default)
			)
			(layer "F.Fab")
		)
		(fp_line
			(start -0.12065 0.3048)
			(end -0.67945 0.3048)
			(stroke
				(width 0.1)
				(type default)
			)
			(layer "F.Fab")
		)
		(fp_line
			(start 0.120396 0.2794)
			(end -0.12065 0.2794)
			(stroke
				(width 0.1)
				(type default)
			)
			(layer "F.Fab")
		)
		(fp_line
			(start 0.120396 0.3048)
			(end 0.120396 0.2794)
			(stroke
				(width 0.1)
				(type default)
			)
			(layer "F.Fab")
		)
		(fp_line
			(start 0.12065 -0.3048)
			(end 0.67945 -0.3048)
			(stroke
				(width 0.1)
				(type default)
			)
			(layer "F.Fab")
		)
		(fp_line
			(start 0.12065 -0.2794)
			(end 0.12065 -0.3048)
			(stroke
				(width 0.1)
				(type default)
			)
			(layer "F.Fab")
		)
		(fp_line
			(start 0.67945 -0.3048)
			(end 0.67945 0.3048)
			(stroke
				(width 0.1)
				(type default)
			)
			(layer "F.Fab")
		)
		(fp_line
			(start 0.67945 0.3048)
			(end 0.120396 0.3048)
			(stroke
				(width 0.1)
				(type default)
			)
			(layer "F.Fab")
		)
		(pad "1" smd circle
			(at -0.40005 0)
			(size 0 0)
			(layers "F.Cu" "F.Mask" "F.Paste")
			(net "P1V05_PCH_AUX")
		)
		(pad "2" smd circle
			(at 0.40005 0)
			(size 0 0)
			(layers "F.Cu" "F.Mask" "F.Paste")
			(net "FAB_REV_ID0")
		)
	)
	(footprint ""
		(layer "F.Cu")
		(at 58.93308 -39.148004)
		(property "Reference" "R4060"
			(at 0 0 0)
			(layer "F.SilkS")
			(hide yes)
			(effects
				(font
					(size 1.27 1.27)
				)
			)
		)
		(property "Value" ""
			(at 0 0 0)
			(layer "F.Fab")
			(effects
				(font
					(size 1.27 1.27)
				)
			)
		)
		(duplicate_pad_numbers_are_jumpers no)
		(fp_line
			(start -0.7874 -0.4064)
			(end 0.7874 -0.4064)
			(stroke
				(width 0.1524)
				(type default)
			)
			(layer "F.SilkS")
		)
		(fp_line
			(start -0.7874 0.4064)
			(end -0.7874 -0.4064)
			(stroke
				(width 0.1524)
				(type default)
			)
			(layer "F.SilkS")
		)
		(fp_line
			(start 0.7874 -0.4064)
			(end 0.7874 0.4064)
			(stroke
				(width 0.1524)
				(type default)
			)
			(layer "F.SilkS")
		)
		(fp_line
			(start 0.7874 0.4064)
			(end -0.7874 0.4064)
			(stroke
				(width 0.1524)
				(type default)
			)
			(layer "F.SilkS")
		)
		(fp_line
			(start -0.67945 -0.305054)
			(end -0.12065 -0.305054)
			(stroke
				(width 0.1)
				(type default)
			)
			(layer "F.Fab")
		)
		(fp_line
			(start -0.67945 0.3048)
			(end -0.67945 -0.305054)
			(stroke
				(width 0.1)
				(type default)
			)
			(layer "F.Fab")
		)
		(fp_line
			(start -0.12065 -0.305054)
			(end -0.12065 -0.2794)
			(stroke
				(width 0.1)
				(type default)
			)
			(layer "F.Fab")
		)
		(fp_line
			(start -0.12065 -0.2794)
			(end 0.12065 -0.2794)
			(stroke
				(width 0.1)
				(type default)
			)
			(layer "F.Fab")
		)
		(fp_line
			(start -0.12065 0.2794)
			(end -0.12065 0.3048)
			(stroke
				(width 0.1)
				(type default)
			)
			(layer "F.Fab")
		)
		(fp_line
			(start -0.12065 0.3048)
			(end -0.67945 0.3048)
			(stroke
				(width 0.1)
				(type default)
			)
			(layer "F.Fab")
		)
		(fp_line
			(start 0.120396 0.2794)
			(end -0.12065 0.2794)
			(stroke
				(width 0.1)
				(type default)
			)
			(layer "F.Fab")
		)
		(fp_line
			(start 0.120396 0.3048)
			(end 0.120396 0.2794)
			(stroke
				(width 0.1)
				(type default)
			)
			(layer "F.Fab")
		)
		(fp_line
			(start 0.12065 -0.3048)
			(end 0.67945 -0.3048)
			(stroke
				(width 0.1)
				(type default)
			)
			(layer "F.Fab")
		)
		(fp_line
			(start 0.12065 -0.2794)
			(end 0.12065 -0.3048)
			(stroke
				(width 0.1)
				(type default)
			)
			(layer "F.Fab")
		)
		(fp_line
			(start 0.67945 -0.3048)
			(end 0.67945 0.3048)
			(stroke
				(width 0.1)
				(type default)
			)
			(layer "F.Fab")
		)
		(fp_line
			(start 0.67945 0.3048)
			(end 0.120396 0.3048)
			(stroke
				(width 0.1)
				(type default)
			)
			(layer "F.Fab")
		)
		(pad "1" smd circle
			(at -0.40005 0)
			(size 0 0)
			(layers "F.Cu" "F.Mask" "F.Paste")
			(net "HP_LVC3_OCP_V3_2_EN")
		)
		(pad "2" smd circle
			(at 0.40005 0)
			(size 0 0)
			(layers "F.Cu" "F.Mask" "F.Paste")
			(net "P3V3_OCP_EN_2_R")
		)
	)
	(footprint ""
		(layer "F.Cu")
		(at 180.77688 -41.112948)
		(property "Reference" "R2526"
			(at 0 0 0)
			(layer "F.SilkS")
			(hide yes)
			(effects
				(font
					(size 1.27 1.27)
				)
			)
		)
		(property "Value" ""
			(at 0 0 0)
			(layer "F.Fab")
			(effects
				(font
					(size 1.27 1.27)
				)
			)
		)
		(duplicate_pad_numbers_are_jumpers no)
		(fp_line
			(start -0.7874 -0.4064)
			(end 0.7874 -0.4064)
			(stroke
				(width 0.1524)
				(type default)
			)
			(layer "F.SilkS")
		)
		(fp_line
			(start -0.7874 0.4064)
			(end -0.7874 -0.4064)
			(stroke
				(width 0.1524)
				(type default)
			)
			(layer "F.SilkS")
		)
		(fp_line
			(start 0.7874 -0.4064)
			(end 0.7874 0.4064)
			(stroke
				(width 0.1524)
				(type default)
			)
			(layer "F.SilkS")
		)
		(fp_line
			(start 0.7874 0.4064)
			(end -0.7874 0.4064)
			(stroke
				(width 0.1524)
				(type default)
			)
			(layer "F.SilkS")
		)
		(fp_line
			(start -0.67945 -0.305054)
			(end -0.12065 -0.305054)
			(stroke
				(width 0.1)
				(type default)
			)
			(layer "F.Fab")
		)
		(fp_line
			(start -0.67945 0.3048)
			(end -0.67945 -0.305054)
			(stroke
				(width 0.1)
				(type default)
			)
			(layer "F.Fab")
		)
		(fp_line
			(start -0.12065 -0.305054)
			(end -0.12065 -0.2794)
			(stroke
				(width 0.1)
				(type default)
			)
			(layer "F.Fab")
		)
		(fp_line
			(start -0.12065 -0.2794)
			(end 0.12065 -0.2794)
			(stroke
				(width 0.1)
				(type default)
			)
			(layer "F.Fab")
		)
		(fp_line
			(start -0.12065 0.2794)
			(end -0.12065 0.3048)
			(stroke
				(width 0.1)
				(type default)
			)
			(layer "F.Fab")
		)
		(fp_line
			(start -0.12065 0.3048)
			(end -0.67945 0.3048)
			(stroke
				(width 0.1)
				(type default)
			)
			(layer "F.Fab")
		)
		(fp_line
			(start 0.120396 0.2794)
			(end -0.12065 0.2794)
			(stroke
				(width 0.1)
				(type default)
			)
			(layer "F.Fab")
		)
		(fp_line
			(start 0.120396 0.3048)
			(end 0.120396 0.2794)
			(stroke
				(width 0.1)
				(type default)
			)
			(layer "F.Fab")
		)
		(fp_line
			(start 0.12065 -0.3048)
			(end 0.67945 -0.3048)
			(stroke
				(width 0.1)
				(type default)
			)
			(layer "F.Fab")
		)
		(fp_line
			(start 0.12065 -0.2794)
			(end 0.12065 -0.3048)
			(stroke
				(width 0.1)
				(type default)
			)
			(layer "F.Fab")
		)
		(fp_line
			(start 0.67945 -0.3048)
			(end 0.67945 0.3048)
			(stroke
				(width 0.1)
				(type default)
			)
			(layer "F.Fab")
		)
		(fp_line
			(start 0.67945 0.3048)
			(end 0.120396 0.3048)
			(stroke
				(width 0.1)
				(type default)
			)
			(layer "F.Fab")
		)
		(pad "1" smd circle
			(at -0.40005 0)
			(size 0 0)
			(layers "F.Cu" "F.Mask" "F.Paste")
			(net "FM_M2_SSD_0_PEDET")
		)
		(pad "2" smd circle
			(at 0.40005 0)
			(size 0 0)
			(layers "F.Cu" "F.Mask" "F.Paste")
			(net "FM_M2_SSD0_E7_PEDET")
		)
	)
)
